# T6G (Grand Teton) — schematic netlist excerpt (pin names and nets, part order shuffled) for the footprints in the layout excerpt that follows; sources: Cadence DE-HDL packaged netlist, KiCad conversion of 04192023_DAF0TMB3IC0_F0TG_MB_C_brd_V02_OCP.brd

U43  PI3CSW12ZUAEX  IC  pkg UQFN10_0-5_2X1-5  page 186
  \1d+\  = SMB_RT_CPU1_P2_ROM_MUX_1D_SCL
  \1d-\  = SMB_RT_CPU1_P2_ROM_MUX_1D_SDA
  \2d+\  = SMB_RT_CPU1_P2_ROM_MUX_2D_SCL
  \2d-\  = SMB_RT_CPU1_P2_ROM_MUX_2D_SDA
  GND  = GND
  \oe#\  = RT_ROM_MUX4_OE_N
  \d-\  = SMB_RT_CPU1_P2_ROM_R_SDA
  \d+\  = SMB_RT_CPU1_P2_ROM_R_SCL
  S  = FM_SMB_RT_ROM_MUX4_SEL
  VDD  = P3V3_AUX

PR4541  Q_RES  20K 1% CHIP  pkg 0402LF  page 147 : A = P12V_E1S_ISET_0 ; B = P12V_E1S_ISET_0_R

(kicad_pcb
	(version 20260206)
	(generator "pcbnew")
	(generator_version "10.0")
	(general
		(thickness 1.6)
		(legacy_teardrops no)
	)
	(paper "A4")
	(title_block
		(title "04192023_DAF0TMB3IC0_F0TG_MB_C_brd_V02_OCP.brd")
		(comment 1 "Grand Teton / footprints 7371-7372 of 8354")
	)
	(layers
		(0 "F.Cu" signal "TOP")
		(4 "In1.Cu" signal "GND")
		(6 "In2.Cu" signal "IN1")
		(8 "In3.Cu" signal "GND1")
		(10 "In4.Cu" signal "IN2")
		(12 "In5.Cu" signal "GND2")
		(14 "In6.Cu" signal "IN3")
		(16 "In7.Cu" signal "GND3")
		(18 "In8.Cu" signal "VCC")
		(20 "In9.Cu" signal "VCC1")
		(22 "In10.Cu" signal "GND4")
		(24 "In11.Cu" signal "IN4")
		(26 "In12.Cu" signal "GND5")
		(28 "In13.Cu" signal "IN5")
		(30 "In14.Cu" signal "GND6")
		(32 "In15.Cu" signal "IN6")
		(34 "In16.Cu" signal "GND7")
		(2 "B.Cu" signal "BOTTOM")
		(9 "F.Adhes" user "F.Adhesive")
		(11 "B.Adhes" user "B.Adhesive")
		(13 "F.Paste" user "Package Geometry/Pastemask Top")
		(15 "B.Paste" user "Package Geometry/Pastemask Bottom")
		(5 "F.SilkS" user "Ref Des/Silkscreen Top")
		(7 "B.SilkS" user "Ref Des/Silkscreen Bottom")
		(1 "F.Mask" user "Board Geometry/Soldermask Top")
		(3 "B.Mask" user "Board Geometry/Soldermask Bottom")
		(17 "Dwgs.User" user "User.Drawings")
		(19 "Cmts.User" user "User.Comments")
		(21 "Eco1.User" user "User.Eco1")
		(23 "Eco2.User" user "User.Eco2")
		(25 "Edge.Cuts" user "Board Geometry/Outline")
		(27 "Margin" user)
		(31 "F.CrtYd" user "Package Geometry/Place Bound Top")
		(29 "B.CrtYd" user "Package Geometry/Place Bound Bottom")
		(35 "F.Fab" user "Ref Des/Assembly Top")
		(33 "B.Fab" user "Ref Des/Assembly Bottom")
	)
	(footprint ""
		(layer "B.Cu")
		(at 160.103312 -417.50488 180)
		(property "Reference" "U43"
			(at -0.04318 -3.007106 0)
			(unlocked yes)
			(layer "B.SilkS")
			(effects
				(font
					(size 0.7874 0.5842)
					(thickness 0.1524)
				)
				(justify mirror)
			)
		)
		(property "Value" ""
			(at 0 0 0)
			(layer "B.Fab")
			(effects
				(font
					(size 1.27 1.27)
				)
				(justify mirror)
			)
		)
		(duplicate_pad_numbers_are_jumpers no)
		(fp_line
			(start 1.03378 1.284478)
			(end 1.03378 -1.284478)
			(stroke
				(width 0.1524)
				(type default)
			)
			(layer "B.SilkS")
		)
		(fp_line
			(start 1.03378 -1.284478)
			(end -1.03378 -1.284478)
			(stroke
				(width 0.1524)
				(type default)
			)
			(layer "B.SilkS")
		)
		(fp_line
			(start -1.03378 1.284478)
			(end 1.03378 1.284478)
			(stroke
				(width 0.1524)
				(type default)
			)
			(layer "B.SilkS")
		)
		(fp_line
			(start -1.03378 -1.284478)
			(end -1.03378 1.284478)
			(stroke
				(width 0.1524)
				(type default)
			)
			(layer "B.SilkS")
		)
		(fp_poly
			(pts
				(xy 1.183132 -0.700532) (xy 1.6129 -0.178308) (xy 1.858772 -0.731012)
			)
			(stroke
				(width 0)
				(type default)
			)
			(fill yes)
			(layer "B.SilkS")
		)
		(fp_line
			(start 0.774954 1.02489)
			(end 0.774954 -1.02489)
			(stroke
				(width 0.1)
				(type default)
			)
			(layer "B.Fab")
		)
		(fp_line
			(start 0.774954 -1.02489)
			(end -0.774954 -1.02489)
			(stroke
				(width 0.1)
				(type default)
			)
			(layer "B.Fab")
		)
		(fp_line
			(start -0.774954 1.02489)
			(end 0.774954 1.02489)
			(stroke
				(width 0.1)
				(type default)
			)
			(layer "B.Fab")
		)
		(fp_line
			(start -0.774954 -1.02489)
			(end -0.774954 1.02489)
			(stroke
				(width 0.1)
				(type default)
			)
			(layer "B.Fab")
		)
		(fp_poly
			(pts
				(xy 1.201674 -0.750062) (xy 1.806702 -0.447548) (xy 1.806702 -1.052576)
			)
			(stroke
				(width 0)
				(type default)
			)
			(fill yes)
			(layer "B.Fab")
		)
		(pad "1" smd rect
			(at 0.64008 -0.750062 270)
			(size 0.3048 0.5334)
			(layers "B.Cu" "B.Mask" "B.Paste")
			(net "SMB_RT_CPU1_P2_ROM_MUX_1D_SCL")
		)
		(pad "2" smd rect
			(at 0.64008 -0.249936 270)
			(size 0.254 0.5334)
			(layers "B.Cu" "B.Mask" "B.Paste")
			(net "SMB_RT_CPU1_P2_ROM_MUX_1D_SDA")
		)
		(pad "3" smd rect
			(at 0.64008 0.249936 270)
			(size 0.254 0.5334)
			(layers "B.Cu" "B.Mask" "B.Paste")
			(net "SMB_RT_CPU1_P2_ROM_MUX_2D_SCL")
		)
		(pad "4" smd rect
			(at 0.64008 0.750062 270)
			(size 0.3048 0.5334)
			(layers "B.Cu" "B.Mask" "B.Paste")
			(net "SMB_RT_CPU1_P2_ROM_MUX_2D_SDA")
		)
		(pad "5" smd rect
			(at 0 0.839978)
			(size 0.3302 0.635)
			(layers "B.Cu" "B.Mask" "B.Paste")
			(net "GND")
		)
		(pad "6" smd rect
			(at -0.64008 0.750062 270)
			(size 0.3048 0.5334)
			(layers "B.Cu" "B.Mask" "B.Paste")
			(net "RT_ROM_MUX4_OE_N")
		)
		(pad "7" smd rect
			(at -0.64008 0.249936 270)
			(size 0.254 0.5334)
			(layers "B.Cu" "B.Mask" "B.Paste")
			(net "SMB_RT_CPU1_P2_ROM_R_SDA")
		)
		(pad "8" smd rect
			(at -0.64008 -0.249936 270)
			(size 0.254 0.5334)
			(layers "B.Cu" "B.Mask" "B.Paste")
			(net "SMB_RT_CPU1_P2_ROM_R_SCL")
		)
		(pad "9" smd rect
			(at -0.64008 -0.750062 270)
			(size 0.3048 0.5334)
			(layers "B.Cu" "B.Mask" "B.Paste")
			(net "FM_SMB_RT_ROM_MUX4_SEL")
		)
		(pad "10" smd rect
			(at 0 -0.839978)
			(size 0.3302 0.635)
			(layers "B.Cu" "B.Mask" "B.Paste")
			(net "P3V3_AUX")
		)
	)
	(footprint ""
		(layer "B.Cu")
		(at 258.208018 -53.118512 90)
		(property "Reference" "PR4541"
			(at 0 0 90)
			(layer "B.SilkS")
			(hide yes)
			(effects
				(font
					(size 1.27 1.27)
				)
				(justify mirror)
			)
		)
		(property "Value" ""
			(at 0 0 90)
			(layer "B.Fab")
			(effects
				(font
					(size 1.27 1.27)
				)
				(justify mirror)
			)
		)
		(duplicate_pad_numbers_are_jumpers no)
		(fp_line
			(start 0.7874 -0.4064)
			(end -0.7874 -0.4064)
			(stroke
				(width 0.1524)
				(type default)
			)
			(layer "B.SilkS")
		)
		(fp_line
			(start -0.7874 -0.4064)
			(end -0.7874 0.4064)
			(stroke
				(width 0.1524)
				(type default)
			)
			(layer "B.SilkS")
		)
		(fp_line
			(start 0.7874 0.4064)
			(end 0.7874 -0.4064)
			(stroke
				(width 0.1524)
				(type default)
			)
			(layer "B.SilkS")
		)
		(fp_line
			(start -0.7874 0.4064)
			(end 0.7874 0.4064)
			(stroke
				(width 0.1524)
				(type default)
			)
			(layer "B.SilkS")
		)
		(fp_line
			(start 0.67945 -0.305054)
			(end 0.12065 -0.305054)
			(stroke
				(width 0.1)
				(type default)
			)
			(layer "B.Fab")
		)
		(fp_line
			(start 0.12065 -0.305054)
			(end 0.12065 -0.2794)
			(stroke
				(width 0.1)
				(type default)
			)
			(layer "B.Fab")
		)
		(fp_line
			(start -0.12065 -0.3048)
			(end -0.67945 -0.3048)
			(stroke
				(width 0.1)
				(type default)
			)
			(layer "B.Fab")
		)
		(fp_line
			(start -0.67945 -0.3048)
			(end -0.67945 0.3048)
			(stroke
				(width 0.1)
				(type default)
			)
			(layer "B.Fab")
		)
		(fp_line
			(start 0.12065 -0.2794)
			(end -0.12065 -0.2794)
			(stroke
				(width 0.1)
				(type default)
			)
			(layer "B.Fab")
		)
		(fp_line
			(start -0.12065 -0.2794)
			(end -0.12065 -0.3048)
			(stroke
				(width 0.1)
				(type default)
			)
			(layer "B.Fab")
		)
		(fp_line
			(start 0.12065 0.2794)
			(end 0.12065 0.3048)
			(stroke
				(width 0.1)
				(type default)
			)
			(layer "B.Fab")
		)
		(fp_line
			(start -0.120396 0.2794)
			(end 0.12065 0.2794)
			(stroke
				(width 0.1)
				(type default)
			)
			(layer "B.Fab")
		)
		(fp_line
			(start 0.67945 0.3048)
			(end 0.67945 -0.305054)
			(stroke
				(width 0.1)
				(type default)
			)
			(layer "B.Fab")
		)
		(fp_line
			(start 0.12065 0.3048)
			(end 0.67945 0.3048)
			(stroke
				(width 0.1)
				(type default)
			)
			(layer "B.Fab")
		)
		(fp_line
			(start -0.120396 0.3048)
			(end -0.120396 0.2794)
			(stroke
				(width 0.1)
				(type default)
			)
			(layer "B.Fab")
		)
		(fp_line
			(start -0.67945 0.3048)
			(end -0.120396 0.3048)
			(stroke
				(width 0.1)
				(type default)
			)
			(layer "B.Fab")
		)
		(pad "1" smd circle
			(at 0.40005 0 270)
			(size 0 0)
			(layers "B.Cu" "B.Mask" "B.Paste")
			(net "P12V_E1S_ISET_0")
		)
		(pad "2" smd circle
			(at -0.40005 0 270)
			(size 0 0)
			(layers "B.Cu" "B.Mask" "B.Paste")
			(net "P12V_E1S_ISET_0_R")
		)
	)
)
